# TIMECARD (Time Appliance Project (Time Card)) — schematic netlist excerpt (pin names and nets, part order shuffled) for the footprints in the layout excerpt that follows; sources: Cadence DE-HDL packaged netlist, KiCad conversion of R4006-B0001-02_R01.brd

C30  CAPACITOR  10UF 25V 20%  pkg SMC_0805R_H057  page 32 : \1\ = VIN_XP5R0V ; \2\ = SG
R452  RESISTOR  4.7KOHM 1%  pkg SMC_0402R_H016  page 24 : \1\ = UNNAMED_524_POWERMOS3PNCHV1_I44 ; \2\ = XP3R3V_FPGA

(kicad_pcb
	(version 20260206)
	(generator "pcbnew")
	(generator_version "10.0")
	(general
		(thickness 1.6)
		(legacy_teardrops no)
	)
	(paper "A4")
	(title_block
		(title "timecard-production-celestica-r4006 — R4006-B0001-02_R01.brd")
		(comment 1 "Time Appliance Project (Time Card) / footprints 241-242 of 1113")
	)
	(layers
		(0 "F.Cu" signal "TOP")
		(4 "In1.Cu" signal "L02_GND1")
		(6 "In2.Cu" signal "L03_SIG1")
		(8 "In3.Cu" signal "L04_GND2")
		(10 "In4.Cu" signal "L05_VCC1")
		(12 "In5.Cu" signal "L06_VCC2")
		(14 "In6.Cu" signal "L07_GND3")
		(16 "In7.Cu" signal "L08_SIG2")
		(18 "In8.Cu" signal "L09_GND4")
		(2 "B.Cu" signal "BOTTOM")
		(9 "F.Adhes" user "F.Adhesive")
		(11 "B.Adhes" user "B.Adhesive")
		(13 "F.Paste" user "Package Geometry/Pastemask Top")
		(15 "B.Paste" user "Package Geometry/Pastemask Bottom")
		(5 "F.SilkS" user "Ref Des/Silkscreen Top")
		(7 "B.SilkS" user "Ref Des/Silkscreen Bottom")
		(1 "F.Mask" user "Board Geometry/Soldermask Top")
		(3 "B.Mask" user "Board Geometry/Soldermask Bottom")
		(17 "Dwgs.User" user "User.Drawings")
		(19 "Cmts.User" user "User.Comments")
		(21 "Eco1.User" user "User.Eco1")
		(23 "Eco2.User" user "User.Eco2")
		(25 "Edge.Cuts" user "Board Geometry/Outline")
		(27 "Margin" user)
		(31 "F.CrtYd" user "Package Geometry/Place Bound Top")
		(29 "B.CrtYd" user "Package Geometry/Place Bound Bottom")
		(35 "F.Fab" user "Ref Des/Assembly Top")
		(33 "B.Fab" user "Ref Des/Assembly Bottom")
	)
	(footprint ""
		(layer "F.Cu")
		(at 42.6974 -105.4354)
		(property "Reference" "C30"
			(at 3.6576 -1.21793 0)
			(unlocked yes)
			(layer "F.SilkS")
			(effects
				(font
					(size 0.7874 0.5842)
					(thickness 0.1524)
				)
			)
		)
		(property "Value" "VAL*"
			(at 0.0762 3.134106 0)
			(unlocked yes)
			(layer "F.Fab")
			(hide yes)
			(effects
				(font
					(size 0.7874 0.5842)
					(thickness 0.1524)
				)
			)
		)
		(property "Device Type" "CAPACITOR-G107-0F106-EM,10UF,2A"
			(at 0.0508 2.194306 0)
			(unlocked yes)
			(layer "F.Fab")
			(hide yes)
			(effects
				(font
					(size 0.7874 0.5842)
					(thickness 0.1524)
				)
			)
		)
		(property "User Part Number" "PARTNUM*"
			(at 0.1016 5.013706 0)
			(unlocked yes)
			(layer "Cmts.User")
			(hide yes)
			(effects
				(font
					(size 0.7874 0.5842)
					(thickness 0.1524)
				)
			)
		)
		(property "Tolerance" "TOL*"
			(at 0.0762 4.048506 0)
			(unlocked yes)
			(layer "Cmts.User")
			(hide yes)
			(effects
				(font
					(size 0.7874 0.5842)
					(thickness 0.1524)
				)
			)
		)
		(duplicate_pad_numbers_are_jumpers no)
		(fp_line
			(start -1.5748 -0.9398)
			(end -1.5748 0.9398)
			(stroke
				(width 0.1)
				(type default)
			)
			(layer "F.SilkS")
		)
		(fp_line
			(start -1.5748 0.9398)
			(end 1.5748 0.9398)
			(stroke
				(width 0.1)
				(type default)
			)
			(layer "F.SilkS")
		)
		(fp_line
			(start 1.5748 -0.9398)
			(end -1.5748 -0.9398)
			(stroke
				(width 0.1)
				(type default)
			)
			(layer "F.SilkS")
		)
		(fp_line
			(start 1.5748 0.9398)
			(end 1.5748 -0.9398)
			(stroke
				(width 0.1)
				(type default)
			)
			(layer "F.SilkS")
		)
		(fp_rect
			(start 1.5748 -0.9398)
			(end -1.5748 0.9398)
			(stroke
				(width 0)
				(type default)
			)
			(fill no)
			(layer "F.CrtYd")
		)
		(fp_line
			(start -1.016 -0.635)
			(end -1.016 0.635)
			(stroke
				(width 0.1)
				(type default)
			)
			(layer "F.Fab")
		)
		(fp_line
			(start -1.016 0.635)
			(end 1.016 0.635)
			(stroke
				(width 0.1)
				(type default)
			)
			(layer "F.Fab")
		)
		(fp_line
			(start 1.016 -0.635)
			(end -1.016 -0.635)
			(stroke
				(width 0.1)
				(type default)
			)
			(layer "F.Fab")
		)
		(fp_line
			(start 1.016 0.635)
			(end 1.016 -0.635)
			(stroke
				(width 0.1)
				(type default)
			)
			(layer "F.Fab")
		)
		(pad "1" smd rect
			(at -0.8382 0)
			(size 0.9652 1.3716)
			(layers "F.Cu" "F.Mask" "F.Paste")
			(net "VIN_XP5R0V")
		)
		(pad "2" smd rect
			(at 0.8382 0)
			(size 0.9652 1.3716)
			(layers "F.Cu" "F.Mask" "F.Paste")
			(net "SG")
		)
		(zone
			(layer "F.Cu")
			(hatch none 0.5)
			(connect_pads
				(clearance 0)
			)
			(min_thickness 0.25)
			(keepout
				(tracks allowed)
				(vias not_allowed)
				(pads allowed)
				(copperpour not_allowed)
				(footprints allowed)
			)
			(placement
				(enabled no)
				(sheetname "")
			)
			(fill
				(thermal_gap 0.5)
				(thermal_bridge_width 0.5)
				(island_removal_mode 0)
			)
			(polygon
				(pts
					(xy 42.926 -106.0704) (xy 42.4688 -106.0704) (xy 42.4688 -104.8004) (xy 42.926 -104.8004)
				)
			)
		)
	)
	(footprint ""
		(layer "F.Cu")
		(at 111.887 -93.98)
		(property "Reference" "R452"
			(at 3.175 -0.08763 0)
			(unlocked yes)
			(layer "F.SilkS")
			(effects
				(font
					(size 0.7874 0.5842)
					(thickness 0.1524)
				)
			)
		)
		(property "Value" "VAL*"
			(at 0.02032 2.13233 0)
			(unlocked yes)
			(layer "F.Fab")
			(hide yes)
			(effects
				(font
					(size 0.7874 0.5842)
					(thickness 0.1524)
				)
			)
		)
		(property "Tolerance" "TOL*"
			(at 0.044704 3.05435 0)
			(unlocked yes)
			(layer "Cmts.User")
			(hide yes)
			(effects
				(font
					(size 0.7874 0.5842)
					(thickness 0.1524)
				)
			)
		)
		(property "User Part Number" "PARTNUM*"
			(at 0.02032 4.024884 0)
			(unlocked yes)
			(layer "Cmts.User")
			(hide yes)
			(effects
				(font
					(size 0.7874 0.5842)
					(thickness 0.1524)
				)
			)
		)
		(property "Device Type" "RESISTOR-G155-14701-01,4.7KOHMA"
			(at 0.008382 1.210564 0)
			(unlocked yes)
			(layer "F.Fab")
			(hide yes)
			(effects
				(font
					(size 0.7874 0.5842)
					(thickness 0.1524)
				)
			)
		)
		(duplicate_pad_numbers_are_jumpers no)
		(fp_line
			(start -1.143 -0.5588)
			(end -1.143 0.5588)
			(stroke
				(width 0.1)
				(type default)
			)
			(layer "F.SilkS")
		)
		(fp_line
			(start -1.143 0.5588)
			(end 1.143 0.5588)
			(stroke
				(width 0.1)
				(type default)
			)
			(layer "F.SilkS")
		)
		(fp_line
			(start 1.143 -0.5588)
			(end -1.143 -0.5588)
			(stroke
				(width 0.1)
				(type default)
			)
			(layer "F.SilkS")
		)
		(fp_line
			(start 1.143 0.5588)
			(end 1.143 -0.5588)
			(stroke
				(width 0.1)
				(type default)
			)
			(layer "F.SilkS")
		)
		(fp_poly
			(pts
				(xy -1.143 0.5588) (xy 1.143 0.5588) (xy 1.143 -0.5588) (xy -1.143 -0.5588)
			)
			(stroke
				(width 0)
				(type default)
			)
			(fill no)
			(layer "F.CrtYd")
		)
		(fp_line
			(start -0.508 -0.3048)
			(end -0.508 0.3048)
			(stroke
				(width 0.1)
				(type default)
			)
			(layer "F.Fab")
		)
		(fp_line
			(start -0.508 0.3048)
			(end 0.508 0.3048)
			(stroke
				(width 0.1)
				(type default)
			)
			(layer "F.Fab")
		)
		(fp_line
			(start 0.508 -0.3048)
			(end -0.508 -0.3048)
			(stroke
				(width 0.1)
				(type default)
			)
			(layer "F.Fab")
		)
		(fp_line
			(start 0.508 0.3048)
			(end 0.508 -0.3048)
			(stroke
				(width 0.1)
				(type default)
			)
			(layer "F.Fab")
		)
		(pad "1" smd rect
			(at -0.5334 0)
			(size 0.7112 0.6096)
			(layers "F.Cu" "F.Mask" "F.Paste")
			(net "UNNAMED_524_POWERMOS3PNCHV1_I44")
		)
		(pad "2" smd rect
			(at 0.5334 0)
			(size 0.7112 0.6096)
			(layers "F.Cu" "F.Mask" "F.Paste")
			(net "XP3R3V_FPGA")
		)
		(zone
			(layer "F.Cu")
			(hatch none 0.5)
			(connect_pads
				(clearance 0)
			)
			(min_thickness 0.25)
			(keepout
				(tracks allowed)
				(vias not_allowed)
				(pads allowed)
				(copperpour not_allowed)
				(footprints allowed)
			)
			(placement
				(enabled no)
				(sheetname "")
			)
			(fill
				(thermal_gap 0.5)
				(thermal_bridge_width 0.5)
				(island_removal_mode 0)
			)
			(polygon
				(pts
					(xy 111.8108 -93.6752) (xy 111.9632 -93.6752) (xy 111.9632 -94.2848) (xy 111.8108 -94.2848)
				)
			)
		)
		(zone
			(layer "F.Cu")
			(hatch none 0.5)
			(connect_pads
				(clearance 0)
			)
			(min_thickness 0.25)
			(keepout
				(tracks not_allowed)
				(vias allowed)
				(pads allowed)
				(copperpour not_allowed)
				(footprints allowed)
			)
			(placement
				(enabled no)
				(sheetname "")
			)
			(fill
				(thermal_gap 0.5)
				(thermal_bridge_width 0.5)
				(island_removal_mode 0)
			)
			(polygon
				(pts
					(xy 111.8108 -93.6752) (xy 111.9632 -93.6752) (xy 111.9632 -94.2848) (xy 111.8108 -94.2848)
				)
			)
		)
	)
)
